(kicad_pcb
	(version 20260206)
	(generator "pcbnew")
	(generator_version "10.0")
	(general
		(thickness 1.6)
		(legacy_teardrops no)
	)
	(paper "A4")
	(title_block
		(title "01162023_DA0F0TEBIF0_F0T_Expander_BD_F_brd_V02_OCP.brd")
		(comment 1 "Grand Teton / footprints 5951-5957 of 9728")
	)
	(layers
		(0 "F.Cu" signal "TOP")
		(4 "In1.Cu" signal "GND")
		(6 "In2.Cu" signal "VCC")
		(8 "In3.Cu" signal "VCC1")
		(10 "In4.Cu" signal "GND1")
		(12 "In5.Cu" signal "IN1")
		(14 "In6.Cu" signal "GND2")
		(16 "In7.Cu" signal "IN2")
		(18 "In8.Cu" signal "GND3")
		(20 "In9.Cu" signal "IN3")
		(22 "In10.Cu" signal "GND4")
		(24 "In11.Cu" signal "IN4")
		(26 "In12.Cu" signal "GND5")
		(28 "In13.Cu" signal "IN5")
		(30 "In14.Cu" signal "GND6")
		(32 "In15.Cu" signal "IN6")
		(34 "In16.Cu" signal "GND7")
		(2 "B.Cu" signal "BOTTOM")
		(9 "F.Adhes" user "F.Adhesive")
		(11 "B.Adhes" user "B.Adhesive")
		(13 "F.Paste" user "Package Geometry/Pastemask Top")
		(15 "B.Paste" user "Package Geometry/Pastemask Bottom")
		(5 "F.SilkS" user "Ref Des/Silkscreen Top")
		(7 "B.SilkS" user "Ref Des/Silkscreen Bottom")
		(1 "F.Mask" user "Board Geometry/Soldermask Top")
		(3 "B.Mask" user "Board Geometry/Soldermask Bottom")
		(17 "Dwgs.User" user "User.Drawings")
		(19 "Cmts.User" user "User.Comments")
		(21 "Eco1.User" user "User.Eco1")
		(23 "Eco2.User" user "User.Eco2")
		(25 "Edge.Cuts" user "Board Geometry/Outline")
		(27 "Margin" user)
		(31 "F.CrtYd" user "Package Geometry/Place Bound Top")
		(29 "B.CrtYd" user "Package Geometry/Place Bound Bottom")
		(35 "F.Fab" user "Ref Des/Assembly Top")
		(33 "B.Fab" user "Ref Des/Assembly Bottom")
	)
	(footprint ""
		(layer "F.Cu")
		(at 282.473908 -26.31186 -90)
		(property "Reference" "U413"
			(at -0.20574 -2.312162 90)
			(unlocked yes)
			(layer "F.SilkS")
			(effects
				(font
					(size 0.7874 0.5842)
					(thickness 0.1524)
				)
			)
		)
		(property "Value" ""
			(at 0 0 270)
			(layer "F.Fab")
			(effects
				(font
					(size 1.27 1.27)
				)
			)
		)
		(duplicate_pad_numbers_are_jumpers no)
		(fp_line
			(start -1.949958 1.610106)
			(end -1.949958 -1.610106)
			(stroke
				(width 0.1524)
				(type default)
			)
			(layer "F.SilkS")
		)
		(fp_line
			(start 1.949958 1.610106)
			(end -1.949958 1.610106)
			(stroke
				(width 0.1524)
				(type default)
			)
			(layer "F.SilkS")
		)
		(fp_line
			(start 1.949958 -1.560068)
			(end 1.949958 1.610106)
			(stroke
				(width 0.1524)
				(type default)
			)
			(layer "F.SilkS")
		)
		(fp_line
			(start -1.949958 -1.610106)
			(end 1.949958 -1.610106)
			(stroke
				(width 0.1524)
				(type default)
			)
			(layer "F.SilkS")
		)
		(fp_line
			(start -0.750062 1.560068)
			(end -0.750062 -1.560068)
			(stroke
				(width 0.1)
				(type default)
			)
			(layer "F.Fab")
		)
		(fp_line
			(start 0.750062 1.560068)
			(end -0.750062 1.560068)
			(stroke
				(width 0.1)
				(type default)
			)
			(layer "F.Fab")
		)
		(fp_line
			(start -0.750062 -1.560068)
			(end 0.750062 -1.560068)
			(stroke
				(width 0.1)
				(type default)
			)
			(layer "F.Fab")
		)
		(fp_line
			(start 0.750062 -1.560068)
			(end 0.750062 1.560068)
			(stroke
				(width 0.1)
				(type default)
			)
			(layer "F.Fab")
		)
		(pad "D" smd rect
			(at 1.100074 0 180)
			(size 1.016 1.4224)
			(layers "F.Cu" "F.Mask" "F.Paste")
			(net "SSD9_LED_ISO_N")
		)
		(pad "G" smd rect
			(at -1.100074 -0.94996 180)
			(size 1.016 1.4224)
			(layers "F.Cu" "F.Mask" "F.Paste")
			(net "SSD9_LED_R")
		)
		(pad "S" smd rect
			(at -1.100074 0.94996 180)
			(size 1.016 1.4224)
			(layers "F.Cu" "F.Mask" "F.Paste")
			(net "GND")
		)
	)
	(footprint ""
		(layer "F.Cu")
		(at 149.20341 -59.571636 90)
		(property "Reference" "PR262"
			(at 0 0 90)
			(layer "F.SilkS")
			(hide yes)
			(effects
				(font
					(size 1.27 1.27)
				)
			)
		)
		(property "Value" ""
			(at 0 0 90)
			(layer "F.Fab")
			(effects
				(font
					(size 1.27 1.27)
				)
			)
		)
		(duplicate_pad_numbers_are_jumpers no)
		(fp_line
			(start 0.7874 -0.4064)
			(end 0.7874 0.4064)
			(stroke
				(width 0.1524)
				(type default)
			)
			(layer "F.SilkS")
		)
		(fp_line
			(start -0.7874 -0.4064)
			(end 0.7874 -0.4064)
			(stroke
				(width 0.1524)
				(type default)
			)
			(layer "F.SilkS")
		)
		(fp_line
			(start 0.7874 0.4064)
			(end -0.7874 0.4064)
			(stroke
				(width 0.1524)
				(type default)
			)
			(layer "F.SilkS")
		)
		(fp_line
			(start -0.7874 0.4064)
			(end -0.7874 -0.4064)
			(stroke
				(width 0.1524)
				(type default)
			)
			(layer "F.SilkS")
		)
		(fp_line
			(start -0.12065 -0.305054)
			(end -0.12065 -0.2794)
			(stroke
				(width 0.1)
				(type default)
			)
			(layer "F.Fab")
		)
		(fp_line
			(start -0.67945 -0.305054)
			(end -0.12065 -0.305054)
			(stroke
				(width 0.1)
				(type default)
			)
			(layer "F.Fab")
		)
		(fp_line
			(start 0.67945 -0.3048)
			(end 0.67945 0.3048)
			(stroke
				(width 0.1)
				(type default)
			)
			(layer "F.Fab")
		)
		(fp_line
			(start 0.12065 -0.3048)
			(end 0.67945 -0.3048)
			(stroke
				(width 0.1)
				(type default)
			)
			(layer "F.Fab")
		)
		(fp_line
			(start 0.12065 -0.2794)
			(end 0.12065 -0.3048)
			(stroke
				(width 0.1)
				(type default)
			)
			(layer "F.Fab")
		)
		(fp_line
			(start -0.12065 -0.2794)
			(end 0.12065 -0.2794)
			(stroke
				(width 0.1)
				(type default)
			)
			(layer "F.Fab")
		)
		(fp_line
			(start 0.120396 0.2794)
			(end -0.12065 0.2794)
			(stroke
				(width 0.1)
				(type default)
			)
			(layer "F.Fab")
		)
		(fp_line
			(start -0.12065 0.2794)
			(end -0.12065 0.3048)
			(stroke
				(width 0.1)
				(type default)
			)
			(layer "F.Fab")
		)
		(fp_line
			(start 0.67945 0.3048)
			(end 0.120396 0.3048)
			(stroke
				(width 0.1)
				(type default)
			)
			(layer "F.Fab")
		)
		(fp_line
			(start 0.120396 0.3048)
			(end 0.120396 0.2794)
			(stroke
				(width 0.1)
				(type default)
			)
			(layer "F.Fab")
		)
		(fp_line
			(start -0.12065 0.3048)
			(end -0.67945 0.3048)
			(stroke
				(width 0.1)
				(type default)
			)
			(layer "F.Fab")
		)
		(fp_line
			(start -0.67945 0.3048)
			(end -0.67945 -0.305054)
			(stroke
				(width 0.1)
				(type default)
			)
			(layer "F.Fab")
		)
		(pad "1" smd circle
			(at -0.40005 0 90)
			(size 0 0)
			(layers "F.Cu" "F.Mask" "F.Paste")
			(net "P3V3_SSD5_OCP")
		)
		(pad "2" smd circle
			(at 0.40005 0 90)
			(size 0 0)
			(layers "F.Cu" "F.Mask" "F.Paste")
			(net "GND")
		)
	)
	(footprint ""
		(layer "F.Cu")
		(at 364.226602 -121.408952 180)
		(property "Reference" "PC475"
			(at 0 0 180)
			(layer "F.SilkS")
			(hide yes)
			(effects
				(font
					(size 1.27 1.27)
				)
			)
		)
		(property "Value" ""
			(at 0 0 180)
			(layer "F.Fab")
			(effects
				(font
					(size 1.27 1.27)
				)
			)
		)
		(duplicate_pad_numbers_are_jumpers no)
		(fp_line
			(start 1.524 0.762)
			(end -1.524 0.762)
			(stroke
				(width 0.1524)
				(type default)
			)
			(layer "F.SilkS")
		)
		(fp_line
			(start 1.524 -0.762)
			(end 1.524 0.762)
			(stroke
				(width 0.1524)
				(type default)
			)
			(layer "F.SilkS")
		)
		(fp_line
			(start -1.524 0.762)
			(end -1.524 -0.762)
			(stroke
				(width 0.1524)
				(type default)
			)
			(layer "F.SilkS")
		)
		(fp_line
			(start -1.524 -0.762)
			(end 1.524 -0.762)
			(stroke
				(width 0.1524)
				(type default)
			)
			(layer "F.SilkS")
		)
		(fp_line
			(start 1.1049 0.724916)
			(end 1.1049 -0.724916)
			(stroke
				(width 0.1)
				(type default)
			)
			(layer "F.Fab")
		)
		(fp_line
			(start 1.1049 -0.724916)
			(end -1.1049 -0.724916)
			(stroke
				(width 0.1)
				(type default)
			)
			(layer "F.Fab")
		)
		(fp_line
			(start -1.1049 0.724916)
			(end 1.1049 0.724916)
			(stroke
				(width 0.1)
				(type default)
			)
			(layer "F.Fab")
		)
		(fp_line
			(start -1.1049 -0.724916)
			(end -1.1049 0.724916)
			(stroke
				(width 0.1)
				(type default)
			)
			(layer "F.Fab")
		)
		(pad "1" smd rect
			(at -0.889 0)
			(size 1.016 1.27)
			(layers "F.Cu" "F.Mask" "F.Paste")
			(net "GND")
		)
		(pad "2" smd rect
			(at 0.889 0)
			(size 1.016 1.27)
			(layers "F.Cu" "F.Mask" "F.Paste")
			(net "P3V3_AUX")
		)
	)
	(footprint ""
		(layer "F.Cu")
		(at 376.312684 -89.9668)
		(property "Reference" "R1750"
			(at 0 0 0)
			(layer "F.SilkS")
			(hide yes)
			(effects
				(font
					(size 1.27 1.27)
				)
			)
		)
		(property "Value" ""
			(at 0 0 0)
			(layer "F.Fab")
			(effects
				(font
					(size 1.27 1.27)
				)
			)
		)
		(duplicate_pad_numbers_are_jumpers no)
		(fp_line
			(start -0.7874 -0.4064)
			(end 0.7874 -0.4064)
			(stroke
				(width 0.1524)
				(type default)
			)
			(layer "F.SilkS")
		)
		(fp_line
			(start -0.7874 0.4064)
			(end -0.7874 -0.4064)
			(stroke
				(width 0.1524)
				(type default)
			)
			(layer "F.SilkS")
		)
		(fp_line
			(start 0.7874 -0.4064)
			(end 0.7874 0.4064)
			(stroke
				(width 0.1524)
				(type default)
			)
			(layer "F.SilkS")
		)
		(fp_line
			(start 0.7874 0.4064)
			(end -0.7874 0.4064)
			(stroke
				(width 0.1524)
				(type default)
			)
			(layer "F.SilkS")
		)
		(fp_line
			(start -0.67945 -0.305054)
			(end -0.12065 -0.305054)
			(stroke
				(width 0.1)
				(type default)
			)
			(layer "F.Fab")
		)
		(fp_line
			(start -0.67945 0.3048)
			(end -0.67945 -0.305054)
			(stroke
				(width 0.1)
				(type default)
			)
			(layer "F.Fab")
		)
		(fp_line
			(start -0.12065 -0.305054)
			(end -0.12065 -0.2794)
			(stroke
				(width 0.1)
				(type default)
			)
			(layer "F.Fab")
		)
		(fp_line
			(start -0.12065 -0.2794)
			(end 0.12065 -0.2794)
			(stroke
				(width 0.1)
				(type default)
			)
			(layer "F.Fab")
		)
		(fp_line
			(start -0.12065 0.2794)
			(end -0.12065 0.3048)
			(stroke
				(width 0.1)
				(type default)
			)
			(layer "F.Fab")
		)
		(fp_line
			(start -0.12065 0.3048)
			(end -0.67945 0.3048)
			(stroke
				(width 0.1)
				(type default)
			)
			(layer "F.Fab")
		)
		(fp_line
			(start 0.120396 0.2794)
			(end -0.12065 0.2794)
			(stroke
				(width 0.1)
				(type default)
			)
			(layer "F.Fab")
		)
		(fp_line
			(start 0.120396 0.3048)
			(end 0.120396 0.2794)
			(stroke
				(width 0.1)
				(type default)
			)
			(layer "F.Fab")
		)
		(fp_line
			(start 0.12065 -0.3048)
			(end 0.67945 -0.3048)
			(stroke
				(width 0.1)
				(type default)
			)
			(layer "F.Fab")
		)
		(fp_line
			(start 0.12065 -0.2794)
			(end 0.12065 -0.3048)
			(stroke
				(width 0.1)
				(type default)
			)
			(layer "F.Fab")
		)
		(fp_line
			(start 0.67945 -0.3048)
			(end 0.67945 0.3048)
			(stroke
				(width 0.1)
				(type default)
			)
			(layer "F.Fab")
		)
		(fp_line
			(start 0.67945 0.3048)
			(end 0.120396 0.3048)
			(stroke
				(width 0.1)
				(type default)
			)
			(layer "F.Fab")
		)
		(pad "1" smd circle
			(at -0.40005 0)
			(size 0 0)
			(layers "F.Cu" "F.Mask" "F.Paste")
			(net "P3V3_AUX")
		)
		(pad "2" smd circle
			(at 0.40005 0)
			(size 0 0)
			(layers "F.Cu" "F.Mask" "F.Paste")
			(net "BIC_I2C6_MUX_A1")
		)
	)
	(footprint ""
		(layer "F.Cu")
		(at 51.064414 -29.079952 180)
		(property "Reference" "R6199"
			(at 0 0 180)
			(layer "F.SilkS")
			(hide yes)
			(effects
				(font
					(size 1.27 1.27)
				)
			)
		)
		(property "Value" ""
			(at 0 0 180)
			(layer "F.Fab")
			(effects
				(font
					(size 1.27 1.27)
				)
			)
		)
		(duplicate_pad_numbers_are_jumpers no)
		(fp_line
			(start 0.7874 0.4064)
			(end -0.7874 0.4064)
			(stroke
				(width 0.1524)
				(type default)
			)
			(layer "F.SilkS")
		)
		(fp_line
			(start 0.7874 -0.4064)
			(end 0.7874 0.4064)
			(stroke
				(width 0.1524)
				(type default)
			)
			(layer "F.SilkS")
		)
		(fp_line
			(start -0.7874 0.4064)
			(end -0.7874 -0.4064)
			(stroke
				(width 0.1524)
				(type default)
			)
			(layer "F.SilkS")
		)
		(fp_line
			(start -0.7874 -0.4064)
			(end 0.7874 -0.4064)
			(stroke
				(width 0.1524)
				(type default)
			)
			(layer "F.SilkS")
		)
		(fp_line
			(start 0.67945 0.3048)
			(end 0.120396 0.3048)
			(stroke
				(width 0.1)
				(type default)
			)
			(layer "F.Fab")
		)
		(fp_line
			(start 0.67945 -0.3048)
			(end 0.67945 0.3048)
			(stroke
				(width 0.1)
				(type default)
			)
			(layer "F.Fab")
		)
		(fp_line
			(start 0.12065 -0.2794)
			(end 0.12065 -0.3048)
			(stroke
				(width 0.1)
				(type default)
			)
			(layer "F.Fab")
		)
		(fp_line
			(start 0.12065 -0.3048)
			(end 0.67945 -0.3048)
			(stroke
				(width 0.1)
				(type default)
			)
			(layer "F.Fab")
		)
		(fp_line
			(start 0.120396 0.3048)
			(end 0.120396 0.2794)
			(stroke
				(width 0.1)
				(type default)
			)
			(layer "F.Fab")
		)
		(fp_line
			(start 0.120396 0.2794)
			(end -0.12065 0.2794)
			(stroke
				(width 0.1)
				(type default)
			)
			(layer "F.Fab")
		)
		(fp_line
			(start -0.12065 0.3048)
			(end -0.67945 0.3048)
			(stroke
				(width 0.1)
				(type default)
			)
			(layer "F.Fab")
		)
		(fp_line
			(start -0.12065 0.2794)
			(end -0.12065 0.3048)
			(stroke
				(width 0.1)
				(type default)
			)
			(layer "F.Fab")
		)
		(fp_line
			(start -0.12065 -0.2794)
			(end 0.12065 -0.2794)
			(stroke
				(width 0.1)
				(type default)
			)
			(layer "F.Fab")
		)
		(fp_line
			(start -0.12065 -0.305054)
			(end -0.12065 -0.2794)
			(stroke
				(width 0.1)
				(type default)
			)
			(layer "F.Fab")
		)
		(fp_line
			(start -0.67945 0.3048)
			(end -0.67945 -0.305054)
			(stroke
				(width 0.1)
				(type default)
			)
			(layer "F.Fab")
		)
		(fp_line
			(start -0.67945 -0.305054)
			(end -0.12065 -0.305054)
			(stroke
				(width 0.1)
				(type default)
			)
			(layer "F.Fab")
		)
		(pad "1" smd circle
			(at -0.40005 0 180)
			(size 0 0)
			(layers "F.Cu" "F.Mask" "F.Paste")
			(net "GND")
		)
		(pad "2" smd circle
			(at 0.40005 0 180)
			(size 0 0)
			(layers "F.Cu" "F.Mask" "F.Paste")
			(net "SSD1_PWRDIS_R")
		)
	)
	(footprint ""
		(layer "F.Cu")
		(at 401.073112 -232.818432)
		(property "Reference" "J65"
			(at -7.126986 0.264668 0)
			(unlocked yes)
			(layer "F.SilkS")
			(effects
				(font
					(size 0.7874 0.5842)
					(thickness 0.1524)
				)
				(justify left)
			)
		)
		(property "Value" ""
			(at 0 0 0)
			(layer "F.Fab")
			(effects
				(font
					(size 1.27 1.27)
				)
			)
		)
		(duplicate_pad_numbers_are_jumpers no)
		(fp_line
			(start -1.27 -3.81)
			(end 1.27 -3.81)
			(stroke
				(width 0.1524)
				(type default)
			)
			(layer "F.SilkS")
		)
		(fp_line
			(start -1.27 -0.7747)
			(end -1.27 -3.81)
			(stroke
				(width 0.1524)
				(type default)
			)
			(layer "F.SilkS")
		)
		(fp_line
			(start -1.27 3.81)
			(end -1.27 0.7747)
			(stroke
				(width 0.1524)
				(type default)
			)
			(layer "F.SilkS")
		)
		(fp_line
			(start 1.27 -3.81)
			(end 1.27 -3.3147)
			(stroke
				(width 0.1524)
				(type default)
			)
			(layer "F.SilkS")
		)
		(fp_line
			(start 1.27 -1.7653)
			(end 1.27 1.7653)
			(stroke
				(width 0.1524)
				(type default)
			)
			(layer "F.SilkS")
		)
		(fp_line
			(start 1.27 3.3147)
			(end 1.27 3.81)
			(stroke
				(width 0.1524)
				(type default)
			)
			(layer "F.SilkS")
		)
		(fp_line
			(start 1.27 3.81)
			(end -1.27 3.81)
			(stroke
				(width 0.1524)
				(type default)
			)
			(layer "F.SilkS")
		)
		(fp_poly
			(pts
				(xy 4.3942 -3.048) (xy 4.3942 -2.032) (xy 3.3782 -2.54)
			)
			(stroke
				(width 0)
				(type default)
			)
			(fill yes)
			(layer "F.SilkS")
		)
		(fp_line
			(start -1.27 -3.81)
			(end -1.27 3.81)
			(stroke
				(width 0.1)
				(type default)
			)
			(layer "F.Fab")
		)
		(fp_line
			(start -1.27 3.81)
			(end 1.27 3.81)
			(stroke
				(width 0.1)
				(type default)
			)
			(layer "F.Fab")
		)
		(fp_line
			(start 1.27 -3.81)
			(end -1.27 -3.81)
			(stroke
				(width 0.1)
				(type default)
			)
			(layer "F.Fab")
		)
		(fp_line
			(start 1.27 3.81)
			(end 1.27 -3.81)
			(stroke
				(width 0.1)
				(type default)
			)
			(layer "F.Fab")
		)
		(fp_poly
			(pts
				(xy 4.3942 -3.048) (xy 4.3942 -2.032) (xy 3.3782 -2.54)
			)
			(stroke
				(width 0)
				(type default)
			)
			(fill yes)
			(layer "F.Fab")
		)
		(fp_text user "3"
			(at 3.921252 2.54 90)
			(unlocked yes)
			(layer "F.SilkS")
			(effects
				(font
					(size 0.7874 0.5842)
					(thickness 0.1524)
				)
			)
		)
		(fp_text user "3"
			(at 3.921252 2.54 90)
			(unlocked yes)
			(layer "F.Fab")
			(effects
				(font
					(size 0.7874 0.5842)
					(thickness 0.1524)
				)
			)
		)
		(pad "1" smd rect
			(at 1.459992 -2.54 90)
			(size 1.27 3.429)
			(layers "F.Cu" "F.Mask" "F.Paste")
			(net "GND")
		)
		(pad "2" smd rect
			(at -1.459992 0 90)
			(size 1.27 3.429)
			(layers "F.Cu" "F.Mask" "F.Paste")
			(net "UART_PEX3_SDB_BUF_R1_TX")
		)
		(pad "3" smd rect
			(at 1.459992 2.54 90)
			(size 1.27 3.429)
			(layers "F.Cu" "F.Mask" "F.Paste")
			(net "UART_PEX3_SDB_R1_RX")
		)
	)
	(footprint ""
		(layer "F.Cu")
		(at 87.77732 -309.791354 135)
		(property "Reference" "R1243"
			(at 0 0 135)
			(layer "F.SilkS")
			(hide yes)
			(effects
				(font
					(size 1.27 1.27)
				)
			)
		)
		(property "Value" ""
			(at 0 0 135)
			(layer "F.Fab")
			(effects
				(font
					(size 1.27 1.27)
				)
			)
		)
		(duplicate_pad_numbers_are_jumpers no)
		(fp_line
			(start 0.787389 -0.406267)
			(end 0.787389 0.406267)
			(stroke
				(width 0.1524)
				(type default)
			)
			(layer "F.SilkS")
		)
		(fp_line
			(start 0.787389 0.406267)
			(end -0.787389 0.406267)
			(stroke
				(width 0.1524)
				(type default)
			)
			(layer "F.SilkS")
		)
		(fp_line
			(start -0.787389 -0.406267)
			(end 0.787389 -0.406267)
			(stroke
				(width 0.1524)
				(type default)
			)
			(layer "F.SilkS")
		)
		(fp_line
			(start -0.787389 0.406267)
			(end -0.787389 -0.406267)
			(stroke
				(width 0.1524)
				(type default)
			)
			(layer "F.SilkS")
		)
		(fp_line
			(start 0.679446 -0.30479)
			(end 0.679446 0.30479)
			(stroke
				(width 0.1)
				(type default)
			)
			(layer "F.Fab")
		)
		(fp_line
			(start 0.120515 -0.30479)
			(end 0.679446 -0.30479)
			(stroke
				(width 0.1)
				(type default)
			)
			(layer "F.Fab")
		)
		(fp_line
			(start 0.120695 -0.279466)
			(end 0.120515 -0.30479)
			(stroke
				(width 0.1)
				(type default)
			)
			(layer "F.Fab")
		)
		(fp_line
			(start 0.679446 0.30479)
			(end 0.120515 0.30479)
			(stroke
				(width 0.1)
				(type default)
			)
			(layer "F.Fab")
		)
		(fp_line
			(start -0.120695 -0.304969)
			(end -0.120695 -0.279466)
			(stroke
				(width 0.1)
				(type default)
			)
			(layer "F.Fab")
		)
		(fp_line
			(start -0.120695 -0.279466)
			(end 0.120695 -0.279466)
			(stroke
				(width 0.1)
				(type default)
			)
			(layer "F.Fab")
		)
		(fp_line
			(start 0.120335 0.279466)
			(end -0.120695 0.279466)
			(stroke
				(width 0.1)
				(type default)
			)
			(layer "F.Fab")
		)
		(fp_line
			(start 0.120515 0.30479)
			(end 0.120335 0.279466)
			(stroke
				(width 0.1)
				(type default)
			)
			(layer "F.Fab")
		)
		(fp_line
			(start -0.679446 -0.305149)
			(end -0.120695 -0.304969)
			(stroke
				(width 0.1)
				(type default)
			)
			(layer "F.Fab")
		)
		(fp_line
			(start -0.120695 0.279466)
			(end -0.120515 0.30479)
			(stroke
				(width 0.1)
				(type default)
			)
			(layer "F.Fab")
		)
		(fp_line
			(start -0.120515 0.30479)
			(end -0.679446 0.30479)
			(stroke
				(width 0.1)
				(type default)
			)
			(layer "F.Fab")
		)
		(fp_line
			(start -0.679446 0.30479)
			(end -0.679446 -0.305149)
			(stroke
				(width 0.1)
				(type default)
			)
			(layer "F.Fab")
		)
		(pad "1" smd circle
			(at -0.40005 0 135)
			(size 0 0)
			(layers "F.Cu" "F.Mask" "F.Paste")
			(net "PEX0_SPARE7")
		)
		(pad "2" smd circle
			(at 0.40005 0 135)
			(size 0 0)
			(layers "F.Cu" "F.Mask" "F.Paste")
			(net "P1V8_PEX")
		)
	)
)
